(kicad_pcb
	(version 20260206)
	(generator "pcbnew")
	(generator_version "10.0")
	(general
		(thickness 1.6)
		(legacy_teardrops no)
	)
	(paper "A4")
	(title_block
		(title "12092022_DA0F0TFB6D0_F0T_FAN_BOARD_MP5048_D_brd_v02_OCP.brd")
		(comment 1 "Grand Teton / footprints 92-97 of 924")
	)
	(layers
		(0 "F.Cu" signal "TOP")
		(4 "In1.Cu" signal "GND")
		(6 "In2.Cu" signal "IN1")
		(8 "In3.Cu" signal "IN2")
		(10 "In4.Cu" signal "GND1")
		(2 "B.Cu" signal "BOTTOM")
		(9 "F.Adhes" user "F.Adhesive")
		(11 "B.Adhes" user "B.Adhesive")
		(13 "F.Paste" user "Package Geometry/Pastemask Top")
		(15 "B.Paste" user "Package Geometry/Pastemask Bottom")
		(5 "F.SilkS" user "Ref Des/Silkscreen Top")
		(7 "B.SilkS" user "Ref Des/Silkscreen Bottom")
		(1 "F.Mask" user "Board Geometry/Soldermask Top")
		(3 "B.Mask" user "Board Geometry/Soldermask Bottom")
		(17 "Dwgs.User" user "User.Drawings")
		(19 "Cmts.User" user "User.Comments")
		(21 "Eco1.User" user "User.Eco1")
		(23 "Eco2.User" user "User.Eco2")
		(25 "Edge.Cuts" user "Board Geometry/Outline")
		(27 "Margin" user)
		(31 "F.CrtYd" user "Package Geometry/Place Bound Top")
		(29 "B.CrtYd" user "Package Geometry/Place Bound Bottom")
		(35 "F.Fab" user "Ref Des/Assembly Top")
		(33 "B.Fab" user "Ref Des/Assembly Bottom")
	)
	(footprint ""
		(layer "F.Cu")
		(at 28.956 -170.561 180)
		(property "Reference" "R5111"
			(at 0 0 180)
			(layer "F.SilkS")
			(hide yes)
			(effects
				(font
					(size 1.27 1.27)
				)
			)
		)
		(property "Value" ""
			(at 0 0 180)
			(layer "F.Fab")
			(effects
				(font
					(size 1.27 1.27)
				)
			)
		)
		(duplicate_pad_numbers_are_jumpers no)
		(fp_line
			(start 0.7874 0.4064)
			(end -0.7874 0.4064)
			(stroke
				(width 0.1524)
				(type default)
			)
			(layer "F.SilkS")
		)
		(fp_line
			(start 0.7874 -0.4064)
			(end 0.7874 0.4064)
			(stroke
				(width 0.1524)
				(type default)
			)
			(layer "F.SilkS")
		)
		(fp_line
			(start -0.7874 0.4064)
			(end -0.7874 -0.4064)
			(stroke
				(width 0.1524)
				(type default)
			)
			(layer "F.SilkS")
		)
		(fp_line
			(start -0.7874 -0.4064)
			(end 0.7874 -0.4064)
			(stroke
				(width 0.1524)
				(type default)
			)
			(layer "F.SilkS")
		)
		(fp_line
			(start 0.67945 0.3048)
			(end 0.120396 0.3048)
			(stroke
				(width 0.1)
				(type default)
			)
			(layer "F.Fab")
		)
		(fp_line
			(start 0.67945 -0.3048)
			(end 0.67945 0.3048)
			(stroke
				(width 0.1)
				(type default)
			)
			(layer "F.Fab")
		)
		(fp_line
			(start 0.12065 -0.2794)
			(end 0.12065 -0.3048)
			(stroke
				(width 0.1)
				(type default)
			)
			(layer "F.Fab")
		)
		(fp_line
			(start 0.12065 -0.3048)
			(end 0.67945 -0.3048)
			(stroke
				(width 0.1)
				(type default)
			)
			(layer "F.Fab")
		)
		(fp_line
			(start 0.120396 0.3048)
			(end 0.120396 0.2794)
			(stroke
				(width 0.1)
				(type default)
			)
			(layer "F.Fab")
		)
		(fp_line
			(start 0.120396 0.2794)
			(end -0.12065 0.2794)
			(stroke
				(width 0.1)
				(type default)
			)
			(layer "F.Fab")
		)
		(fp_line
			(start -0.12065 0.3048)
			(end -0.67945 0.3048)
			(stroke
				(width 0.1)
				(type default)
			)
			(layer "F.Fab")
		)
		(fp_line
			(start -0.12065 0.2794)
			(end -0.12065 0.3048)
			(stroke
				(width 0.1)
				(type default)
			)
			(layer "F.Fab")
		)
		(fp_line
			(start -0.12065 -0.2794)
			(end 0.12065 -0.2794)
			(stroke
				(width 0.1)
				(type default)
			)
			(layer "F.Fab")
		)
		(fp_line
			(start -0.12065 -0.305054)
			(end -0.12065 -0.2794)
			(stroke
				(width 0.1)
				(type default)
			)
			(layer "F.Fab")
		)
		(fp_line
			(start -0.67945 0.3048)
			(end -0.67945 -0.305054)
			(stroke
				(width 0.1)
				(type default)
			)
			(layer "F.Fab")
		)
		(fp_line
			(start -0.67945 -0.305054)
			(end -0.12065 -0.305054)
			(stroke
				(width 0.1)
				(type default)
			)
			(layer "F.Fab")
		)
		(pad "1" smd circle
			(at -0.40005 0 180)
			(size 0 0)
			(layers "F.Cu" "F.Mask" "F.Paste")
			(net "FAN_7_FAIL_LED")
		)
		(pad "2" smd circle
			(at 0.40005 0 180)
			(size 0 0)
			(layers "F.Cu" "F.Mask" "F.Paste")
			(net "FAN_7_FAIL_R_LED")
		)
	)
	(footprint ""
		(layer "F.Cu")
		(at 25.654 -25.654 180)
		(property "Reference" "U67"
			(at 1.05664 1.80467 0)
			(unlocked yes)
			(layer "F.SilkS")
			(effects
				(font
					(size 0.7874 0.5842)
					(thickness 0.1524)
				)
				(justify left)
			)
		)
		(property "Value" ""
			(at 0 0 180)
			(layer "F.Fab")
			(effects
				(font
					(size 1.27 1.27)
				)
			)
		)
		(duplicate_pad_numbers_are_jumpers no)
		(fp_line
			(start 1.538478 1.150874)
			(end 1.538478 -1.150874)
			(stroke
				(width 0.1524)
				(type default)
			)
			(layer "F.SilkS")
		)
		(fp_line
			(start 1.538478 -1.150874)
			(end -1.538478 -1.150874)
			(stroke
				(width 0.1524)
				(type default)
			)
			(layer "F.SilkS")
		)
		(fp_line
			(start -1.538478 1.150874)
			(end 1.538478 1.150874)
			(stroke
				(width 0.1524)
				(type default)
			)
			(layer "F.SilkS")
		)
		(fp_line
			(start -1.538478 -1.150874)
			(end -1.538478 1.150874)
			(stroke
				(width 0.1524)
				(type default)
			)
			(layer "F.SilkS")
		)
		(fp_line
			(start 0.674878 1.100074)
			(end 0.674878 -1.100074)
			(stroke
				(width 0.1)
				(type default)
			)
			(layer "F.Fab")
		)
		(fp_line
			(start 0.674878 -1.100074)
			(end -0.674878 -1.100074)
			(stroke
				(width 0.1)
				(type default)
			)
			(layer "F.Fab")
		)
		(fp_line
			(start -0.674878 1.100074)
			(end 0.674878 1.100074)
			(stroke
				(width 0.1)
				(type default)
			)
			(layer "F.Fab")
		)
		(fp_line
			(start -0.674878 -1.100074)
			(end -0.674878 1.100074)
			(stroke
				(width 0.1)
				(type default)
			)
			(layer "F.Fab")
		)
		(pad "1" smd rect
			(at -0.94996 -0.649986 270)
			(size 0.7112 0.9144)
			(layers "F.Cu" "F.Mask" "F.Paste")
			(net "FAN_3_PWM_IL")
		)
		(pad "2" smd rect
			(at -0.94996 0.649986 270)
			(size 0.7112 0.9144)
			(layers "F.Cu" "F.Mask" "F.Paste")
			(net "FAN_3_PWM_OL")
		)
		(pad "3" smd rect
			(at 0.94996 0 270)
			(size 0.7112 0.9144)
			(layers "F.Cu" "F.Mask" "F.Paste")
			(net "FAN_3_PWM_BUF")
		)
	)
	(footprint ""
		(layer "F.Cu")
		(at 15.621 -173.99)
		(property "Reference" "C1948"
			(at 0 0 0)
			(layer "F.SilkS")
			(hide yes)
			(effects
				(font
					(size 1.27 1.27)
				)
			)
		)
		(property "Value" ""
			(at 0 0 0)
			(layer "F.Fab")
			(effects
				(font
					(size 1.27 1.27)
				)
			)
		)
		(duplicate_pad_numbers_are_jumpers no)
		(fp_line
			(start -0.7874 -0.4064)
			(end 0.7874 -0.4064)
			(stroke
				(width 0.1524)
				(type default)
			)
			(layer "F.SilkS")
		)
		(fp_line
			(start -0.7874 0.4064)
			(end -0.7874 -0.4064)
			(stroke
				(width 0.1524)
				(type default)
			)
			(layer "F.SilkS")
		)
		(fp_line
			(start 0.7874 -0.4064)
			(end 0.7874 0.4064)
			(stroke
				(width 0.1524)
				(type default)
			)
			(layer "F.SilkS")
		)
		(fp_line
			(start 0.7874 0.4064)
			(end -0.7874 0.4064)
			(stroke
				(width 0.1524)
				(type default)
			)
			(layer "F.SilkS")
		)
		(fp_line
			(start -0.67945 -0.305054)
			(end -0.12065 -0.305054)
			(stroke
				(width 0.1)
				(type default)
			)
			(layer "F.Fab")
		)
		(fp_line
			(start -0.67945 0.3048)
			(end -0.67945 -0.305054)
			(stroke
				(width 0.1)
				(type default)
			)
			(layer "F.Fab")
		)
		(fp_line
			(start -0.12065 -0.305054)
			(end -0.12065 -0.2794)
			(stroke
				(width 0.1)
				(type default)
			)
			(layer "F.Fab")
		)
		(fp_line
			(start -0.12065 -0.2794)
			(end 0.12065 -0.2794)
			(stroke
				(width 0.1)
				(type default)
			)
			(layer "F.Fab")
		)
		(fp_line
			(start -0.12065 0.2794)
			(end -0.12065 0.3048)
			(stroke
				(width 0.1)
				(type default)
			)
			(layer "F.Fab")
		)
		(fp_line
			(start -0.12065 0.3048)
			(end -0.67945 0.3048)
			(stroke
				(width 0.1)
				(type default)
			)
			(layer "F.Fab")
		)
		(fp_line
			(start 0.120396 0.2794)
			(end -0.12065 0.2794)
			(stroke
				(width 0.1)
				(type default)
			)
			(layer "F.Fab")
		)
		(fp_line
			(start 0.120396 0.3048)
			(end 0.120396 0.2794)
			(stroke
				(width 0.1)
				(type default)
			)
			(layer "F.Fab")
		)
		(fp_line
			(start 0.12065 -0.3048)
			(end 0.67945 -0.3048)
			(stroke
				(width 0.1)
				(type default)
			)
			(layer "F.Fab")
		)
		(fp_line
			(start 0.12065 -0.2794)
			(end 0.12065 -0.3048)
			(stroke
				(width 0.1)
				(type default)
			)
			(layer "F.Fab")
		)
		(fp_line
			(start 0.67945 -0.3048)
			(end 0.67945 0.3048)
			(stroke
				(width 0.1)
				(type default)
			)
			(layer "F.Fab")
		)
		(fp_line
			(start 0.67945 0.3048)
			(end 0.120396 0.3048)
			(stroke
				(width 0.1)
				(type default)
			)
			(layer "F.Fab")
		)
		(pad "1" smd circle
			(at -0.40005 0)
			(size 0 0)
			(layers "F.Cu" "F.Mask" "F.Paste")
			(net "FAN_7_PRESENT_N")
		)
		(pad "2" smd circle
			(at 0.40005 0)
			(size 0 0)
			(layers "F.Cu" "F.Mask" "F.Paste")
			(net "GND")
		)
	)
	(footprint ""
		(layer "F.Cu")
		(at 21.717 -119.126 90)
		(property "Reference" "C2088"
			(at 0 0 90)
			(layer "F.SilkS")
			(hide yes)
			(effects
				(font
					(size 1.27 1.27)
				)
			)
		)
		(property "Value" ""
			(at 0 0 90)
			(layer "F.Fab")
			(effects
				(font
					(size 1.27 1.27)
				)
			)
		)
		(duplicate_pad_numbers_are_jumpers no)
		(fp_line
			(start 0.7874 -0.4064)
			(end 0.7874 0.4064)
			(stroke
				(width 0.1524)
				(type default)
			)
			(layer "F.SilkS")
		)
		(fp_line
			(start -0.7874 -0.4064)
			(end 0.7874 -0.4064)
			(stroke
				(width 0.1524)
				(type default)
			)
			(layer "F.SilkS")
		)
		(fp_line
			(start 0.7874 0.4064)
			(end -0.7874 0.4064)
			(stroke
				(width 0.1524)
				(type default)
			)
			(layer "F.SilkS")
		)
		(fp_line
			(start -0.7874 0.4064)
			(end -0.7874 -0.4064)
			(stroke
				(width 0.1524)
				(type default)
			)
			(layer "F.SilkS")
		)
		(fp_line
			(start -0.12065 -0.305054)
			(end -0.12065 -0.2794)
			(stroke
				(width 0.1)
				(type default)
			)
			(layer "F.Fab")
		)
		(fp_line
			(start -0.67945 -0.305054)
			(end -0.12065 -0.305054)
			(stroke
				(width 0.1)
				(type default)
			)
			(layer "F.Fab")
		)
		(fp_line
			(start 0.67945 -0.3048)
			(end 0.67945 0.3048)
			(stroke
				(width 0.1)
				(type default)
			)
			(layer "F.Fab")
		)
		(fp_line
			(start 0.12065 -0.3048)
			(end 0.67945 -0.3048)
			(stroke
				(width 0.1)
				(type default)
			)
			(layer "F.Fab")
		)
		(fp_line
			(start 0.12065 -0.2794)
			(end 0.12065 -0.3048)
			(stroke
				(width 0.1)
				(type default)
			)
			(layer "F.Fab")
		)
		(fp_line
			(start -0.12065 -0.2794)
			(end 0.12065 -0.2794)
			(stroke
				(width 0.1)
				(type default)
			)
			(layer "F.Fab")
		)
		(fp_line
			(start 0.120396 0.2794)
			(end -0.12065 0.2794)
			(stroke
				(width 0.1)
				(type default)
			)
			(layer "F.Fab")
		)
		(fp_line
			(start -0.12065 0.2794)
			(end -0.12065 0.3048)
			(stroke
				(width 0.1)
				(type default)
			)
			(layer "F.Fab")
		)
		(fp_line
			(start 0.67945 0.3048)
			(end 0.120396 0.3048)
			(stroke
				(width 0.1)
				(type default)
			)
			(layer "F.Fab")
		)
		(fp_line
			(start 0.120396 0.3048)
			(end 0.120396 0.2794)
			(stroke
				(width 0.1)
				(type default)
			)
			(layer "F.Fab")
		)
		(fp_line
			(start -0.12065 0.3048)
			(end -0.67945 0.3048)
			(stroke
				(width 0.1)
				(type default)
			)
			(layer "F.Fab")
		)
		(fp_line
			(start -0.67945 0.3048)
			(end -0.67945 -0.305054)
			(stroke
				(width 0.1)
				(type default)
			)
			(layer "F.Fab")
		)
		(pad "1" smd circle
			(at -0.40005 0 90)
			(size 0 0)
			(layers "F.Cu" "F.Mask" "F.Paste")
			(net "P3V3_AUX")
		)
		(pad "2" smd circle
			(at 0.40005 0 90)
			(size 0 0)
			(layers "F.Cu" "F.Mask" "F.Paste")
			(net "GND")
		)
	)
	(footprint ""
		(layer "F.Cu")
		(at 37.465 -251.206)
		(property "Reference" "PR27"
			(at 0 0 0)
			(layer "F.SilkS")
			(hide yes)
			(effects
				(font
					(size 1.27 1.27)
				)
			)
		)
		(property "Value" ""
			(at 0 0 0)
			(layer "F.Fab")
			(effects
				(font
					(size 1.27 1.27)
				)
			)
		)
		(duplicate_pad_numbers_are_jumpers no)
		(fp_line
			(start -0.7874 -0.4064)
			(end 0.7874 -0.4064)
			(stroke
				(width 0.1524)
				(type default)
			)
			(layer "F.SilkS")
		)
		(fp_line
			(start -0.7874 0.4064)
			(end -0.7874 -0.4064)
			(stroke
				(width 0.1524)
				(type default)
			)
			(layer "F.SilkS")
		)
		(fp_line
			(start 0.7874 -0.4064)
			(end 0.7874 0.4064)
			(stroke
				(width 0.1524)
				(type default)
			)
			(layer "F.SilkS")
		)
		(fp_line
			(start 0.7874 0.4064)
			(end -0.7874 0.4064)
			(stroke
				(width 0.1524)
				(type default)
			)
			(layer "F.SilkS")
		)
		(fp_line
			(start -0.67945 -0.305054)
			(end -0.12065 -0.305054)
			(stroke
				(width 0.1)
				(type default)
			)
			(layer "F.Fab")
		)
		(fp_line
			(start -0.67945 0.3048)
			(end -0.67945 -0.305054)
			(stroke
				(width 0.1)
				(type default)
			)
			(layer "F.Fab")
		)
		(fp_line
			(start -0.12065 -0.305054)
			(end -0.12065 -0.2794)
			(stroke
				(width 0.1)
				(type default)
			)
			(layer "F.Fab")
		)
		(fp_line
			(start -0.12065 -0.2794)
			(end 0.12065 -0.2794)
			(stroke
				(width 0.1)
				(type default)
			)
			(layer "F.Fab")
		)
		(fp_line
			(start -0.12065 0.2794)
			(end -0.12065 0.3048)
			(stroke
				(width 0.1)
				(type default)
			)
			(layer "F.Fab")
		)
		(fp_line
			(start -0.12065 0.3048)
			(end -0.67945 0.3048)
			(stroke
				(width 0.1)
				(type default)
			)
			(layer "F.Fab")
		)
		(fp_line
			(start 0.120396 0.2794)
			(end -0.12065 0.2794)
			(stroke
				(width 0.1)
				(type default)
			)
			(layer "F.Fab")
		)
		(fp_line
			(start 0.120396 0.3048)
			(end 0.120396 0.2794)
			(stroke
				(width 0.1)
				(type default)
			)
			(layer "F.Fab")
		)
		(fp_line
			(start 0.12065 -0.3048)
			(end 0.67945 -0.3048)
			(stroke
				(width 0.1)
				(type default)
			)
			(layer "F.Fab")
		)
		(fp_line
			(start 0.12065 -0.2794)
			(end 0.12065 -0.3048)
			(stroke
				(width 0.1)
				(type default)
			)
			(layer "F.Fab")
		)
		(fp_line
			(start 0.67945 -0.3048)
			(end 0.67945 0.3048)
			(stroke
				(width 0.1)
				(type default)
			)
			(layer "F.Fab")
		)
		(fp_line
			(start 0.67945 0.3048)
			(end 0.120396 0.3048)
			(stroke
				(width 0.1)
				(type default)
			)
			(layer "F.Fab")
		)
		(pad "1" smd circle
			(at -0.40005 0)
			(size 0 0)
			(layers "F.Cu" "F.Mask" "F.Paste")
			(net "FAN_1_FAULT_R")
		)
		(pad "2" smd circle
			(at 0.40005 0)
			(size 0 0)
			(layers "F.Cu" "F.Mask" "F.Paste")
			(net "FAN_1_P3V_R")
		)
	)
	(footprint ""
		(layer "F.Cu")
		(at 36.322 -103.435912)
		(property "Reference" "D139"
			(at 2.54 0.465582 0)
			(unlocked yes)
			(layer "F.SilkS")
			(effects
				(font
					(size 0.7874 0.5842)
					(thickness 0.1524)
				)
				(justify left)
			)
		)
		(property "Value" ""
			(at 0 0 0)
			(layer "F.Fab")
			(effects
				(font
					(size 1.27 1.27)
				)
			)
		)
		(duplicate_pad_numbers_are_jumpers no)
		(fp_line
			(start -1.651 -0.7112)
			(end 2.032 -0.7112)
			(stroke
				(width 0.1524)
				(type default)
			)
			(layer "F.SilkS")
		)
		(fp_line
			(start -1.651 0.7112)
			(end -1.651 -0.7112)
			(stroke
				(width 0.1524)
				(type default)
			)
			(layer "F.SilkS")
		)
		(fp_line
			(start -0.299974 -0.500126)
			(end -0.299974 0.500126)
			(stroke
				(width 0.1524)
				(type default)
			)
			(layer "F.SilkS")
		)
		(fp_line
			(start -0.299974 0.500126)
			(end 0.199898 0)
			(stroke
				(width 0.1524)
				(type default)
			)
			(layer "F.SilkS")
		)
		(fp_line
			(start 0.199898 0)
			(end -0.299974 -0.500126)
			(stroke
				(width 0.1524)
				(type default)
			)
			(layer "F.SilkS")
		)
		(fp_line
			(start 0.299974 -0.500126)
			(end 0.299974 0.500126)
			(stroke
				(width 0.1524)
				(type default)
			)
			(layer "F.SilkS")
		)
		(fp_line
			(start 1.651 -0.6858)
			(end 1.651 0.6858)
			(stroke
				(width 0.1524)
				(type default)
			)
			(layer "F.SilkS")
		)
		(fp_line
			(start 1.778 0.6858)
			(end 1.778 -0.6858)
			(stroke
				(width 0.1524)
				(type default)
			)
			(layer "F.SilkS")
		)
		(fp_line
			(start 1.905 -0.6858)
			(end 1.905 0.6858)
			(stroke
				(width 0.1524)
				(type default)
			)
			(layer "F.SilkS")
		)
		(fp_line
			(start 2.032 -0.7112)
			(end 2.032 0.7112)
			(stroke
				(width 0.1524)
				(type default)
			)
			(layer "F.SilkS")
		)
		(fp_line
			(start 2.032 0.7112)
			(end -1.651 0.7112)
			(stroke
				(width 0.1524)
				(type default)
			)
			(layer "F.SilkS")
		)
		(fp_line
			(start -1.35001 -0.225044)
			(end -0.899922 -0.225044)
			(stroke
				(width 0.1)
				(type default)
			)
			(layer "F.Fab")
		)
		(fp_line
			(start -1.35001 0.175006)
			(end -1.35001 -0.225044)
			(stroke
				(width 0.1)
				(type default)
			)
			(layer "F.Fab")
		)
		(fp_line
			(start -0.899922 -0.700024)
			(end 0.899922 -0.700024)
			(stroke
				(width 0.1)
				(type default)
			)
			(layer "F.Fab")
		)
		(fp_line
			(start -0.899922 -0.225044)
			(end -0.899922 -0.700024)
			(stroke
				(width 0.1)
				(type default)
			)
			(layer "F.Fab")
		)
		(fp_line
			(start -0.899922 0.175006)
			(end -1.35001 0.175006)
			(stroke
				(width 0.1)
				(type default)
			)
			(layer "F.Fab")
		)
		(fp_line
			(start -0.899922 0.700024)
			(end -0.899922 0.175006)
			(stroke
				(width 0.1)
				(type default)
			)
			(layer "F.Fab")
		)
		(fp_line
			(start -0.299974 -0.500126)
			(end -0.299974 0.500126)
			(stroke
				(width 0.1)
				(type default)
			)
			(layer "F.Fab")
		)
		(fp_line
			(start -0.299974 0.500126)
			(end 0.199898 0)
			(stroke
				(width 0.1)
				(type default)
			)
			(layer "F.Fab")
		)
		(fp_line
			(start 0.199898 0)
			(end -0.299974 -0.500126)
			(stroke
				(width 0.1)
				(type default)
			)
			(layer "F.Fab")
		)
		(fp_line
			(start 0.299974 -0.500126)
			(end 0.299974 0.500126)
			(stroke
				(width 0.1)
				(type default)
			)
			(layer "F.Fab")
		)
		(fp_line
			(start 0.899922 -0.700024)
			(end 0.899922 -0.225044)
			(stroke
				(width 0.1)
				(type default)
			)
			(layer "F.Fab")
		)
		(fp_line
			(start 0.899922 -0.225044)
			(end 1.35001 -0.225044)
			(stroke
				(width 0.1)
				(type default)
			)
			(layer "F.Fab")
		)
		(fp_line
			(start 0.899922 0.175006)
			(end 0.899922 0.700024)
			(stroke
				(width 0.1)
				(type default)
			)
			(layer "F.Fab")
		)
		(fp_line
			(start 0.899922 0.700024)
			(end -0.899922 0.700024)
			(stroke
				(width 0.1)
				(type default)
			)
			(layer "F.Fab")
		)
		(fp_line
			(start 1.35001 -0.225044)
			(end 1.35001 0.175006)
			(stroke
				(width 0.1)
				(type default)
			)
			(layer "F.Fab")
		)
		(fp_line
			(start 1.35001 0.175006)
			(end 0.899922 0.175006)
			(stroke
				(width 0.1)
				(type default)
			)
			(layer "F.Fab")
		)
		(fp_text user "+"
			(at -2.159 1.105662 0)
			(unlocked yes)
			(layer "F.SilkS")
			(effects
				(font
					(size 1.905 1.4224)
					(thickness 0.1524)
				)
				(justify left)
			)
		)
		(fp_text user "-"
			(at 0.889 0.978662 0)
			(unlocked yes)
			(layer "F.SilkS")
			(effects
				(font
					(size 1.905 1.4224)
					(thickness 0.1524)
				)
				(justify left)
			)
		)
		(fp_text user "+"
			(at -2.794 -0.19685 0)
			(unlocked yes)
			(layer "F.Fab")
			(effects
				(font
					(size 1.905 1.4224)
					(thickness 0.1524)
				)
				(justify left)
			)
		)
		(fp_text user "-"
			(at 1.8288 -0.24765 0)
			(unlocked yes)
			(layer "F.Fab")
			(effects
				(font
					(size 1.905 1.4224)
					(thickness 0.1524)
				)
				(justify left)
			)
		)
		(pad "1" smd rect
			(at -1.0922 0 180)
			(size 0.8128 0.8636)
			(layers "F.Cu" "F.Mask" "F.Paste")
			(net "FAN_2_TACH_OL_R")
		)
		(pad "2" smd rect
			(at 1.0922 0)
			(size 0.8128 0.8636)
			(layers "F.Cu" "F.Mask" "F.Paste")
			(net "FAN_2_TACH_OL_D")
		)
	)
)
